# S9S_MB_2U (Grand Teton) — schematic netlist excerpt (pin names and nets, part order shuffled) for the footprints in the layout excerpt that follows; sources: Cadence DE-HDL packaged netlist, KiCad conversion of 03242023_DA0F0TMBIJ0_F0T_Motherboard_J_brd_V01_OCP.brd

U209  PCA9555APW  IC  pkg TSSOP24XB  page 158
  \int#\  = FM_SMB_CPU0_ALERT
  A1  = PD_SMB_OCP1_HP_ADD1
  A2  = PD_SMB_OCP1_HP_ADD2
  P0_0  = TP_PCA9555_0_P00
  P0_1  = TP_PCA9555_0_P01
  P0_2  = HP_OCP_V3_1_EN
  P0_3  = HP_LVC3_OCP_V3_1_ATTN_OUT_SW_N
  P0_4  = HP_LVC3_OCP_V3_1_PRSNT2_N
  P0_5  = TP_PCA9555_0_P5
  P0_6  = TP_PCA9555_0_P6
  P0_7  = TP_PCA9555_0_P7
  VSS  = GND
  P1_0  = TP_PCA9555_0_P10
  P1_1  = TP_PCA9555_0_P11
  P1_2  = TP_PCA9555_0_P12
  P1_3  = TP_PCA9555_0_P13
  P1_4  = TP_PCA9555_0_P14
  P1_5  = TP_PCA9555_0_P15
  P1_6  = TP_PCA9555_0_P16
  P1_7  = TP_PCA9555_0_P17
  A0  = PD_SMB_OCP1_HP_ADD0
  SCL  = SMB_PEHPCPU0_LVC3_R_SCL
  SDA  = SMB_PEHPCPU0_LVC3_R_SDA
  VDD  = P3V3_AUX

(kicad_pcb
	(version 20260206)
	(generator "pcbnew")
	(generator_version "10.0")
	(general
		(thickness 1.6)
		(legacy_teardrops no)
	)
	(paper "A4")
	(title_block
		(title "03242023_DA0F0TMBIJ0_F0T_Motherboard_J_brd_V01_OCP.brd")
		(comment 1 "Grand Teton / footprints 3245-3245 of 6105")
	)
	(layers
		(0 "F.Cu" signal "TOP")
		(4 "In1.Cu" signal "GND")
		(6 "In2.Cu" signal "IN1")
		(8 "In3.Cu" signal "GND1")
		(10 "In4.Cu" signal "IN2")
		(12 "In5.Cu" signal "GND2")
		(14 "In6.Cu" signal "IN3")
		(16 "In7.Cu" signal "GND3")
		(18 "In8.Cu" signal "VCC")
		(20 "In9.Cu" signal "VCC1")
		(22 "In10.Cu" signal "GND4")
		(24 "In11.Cu" signal "IN4")
		(26 "In12.Cu" signal "GND5")
		(28 "In13.Cu" signal "IN5")
		(30 "In14.Cu" signal "GND6")
		(32 "In15.Cu" signal "IN6")
		(34 "In16.Cu" signal "GND7")
		(2 "B.Cu" signal "BOTTOM")
		(9 "F.Adhes" user "F.Adhesive")
		(11 "B.Adhes" user "B.Adhesive")
		(13 "F.Paste" user "Package Geometry/Pastemask Top")
		(15 "B.Paste" user "Package Geometry/Pastemask Bottom")
		(5 "F.SilkS" user "Ref Des/Silkscreen Top")
		(7 "B.SilkS" user "Ref Des/Silkscreen Bottom")
		(1 "F.Mask" user "Board Geometry/Soldermask Top")
		(3 "B.Mask" user "Board Geometry/Soldermask Bottom")
		(17 "Dwgs.User" user "User.Drawings")
		(19 "Cmts.User" user "User.Comments")
		(21 "Eco1.User" user "User.Eco1")
		(23 "Eco2.User" user "User.Eco2")
		(25 "Edge.Cuts" user "Board Geometry/Outline")
		(27 "Margin" user)
		(31 "F.CrtYd" user "Package Geometry/Place Bound Top")
		(29 "B.CrtYd" user "Package Geometry/Place Bound Bottom")
		(35 "F.Fab" user "Ref Des/Assembly Top")
		(33 "B.Fab" user "Ref Des/Assembly Bottom")
	)
	(footprint ""
		(layer "F.Cu")
		(at 457.723748 -114.966496)
		(property "Reference" "U209"
			(at -0.853948 -4.849114 0)
			(unlocked yes)
			(layer "F.SilkS")
			(effects
				(font
					(size 0.7874 0.5842)
					(thickness 0.1524)
				)
				(justify left)
			)
		)
		(property "Value" ""
			(at 0 0 0)
			(layer "F.Fab")
			(effects
				(font
					(size 1.27 1.27)
				)
			)
		)
		(duplicate_pad_numbers_are_jumpers no)
		(fp_line
			(start -2.097532 -3.949954)
			(end -2.097532 3.949954)
			(stroke
				(width 0.1524)
				(type default)
			)
			(layer "F.SilkS")
		)
		(fp_line
			(start -2.097532 3.949954)
			(end 2.097532 3.949954)
			(stroke
				(width 0.1524)
				(type default)
			)
			(layer "F.SilkS")
		)
		(fp_line
			(start -1.409954 -3.949954)
			(end -2.097532 -3.949954)
			(stroke
				(width 0.1524)
				(type default)
			)
			(layer "F.SilkS")
		)
		(fp_line
			(start 0 -2.54)
			(end -1.409954 -3.949954)
			(stroke
				(width 0.1524)
				(type default)
			)
			(layer "F.SilkS")
		)
		(fp_line
			(start 1.409954 -3.949954)
			(end 0 -2.54)
			(stroke
				(width 0.1524)
				(type default)
			)
			(layer "F.SilkS")
		)
		(fp_line
			(start 2.097532 -3.949954)
			(end 1.409954 -3.949954)
			(stroke
				(width 0.1524)
				(type default)
			)
			(layer "F.SilkS")
		)
		(fp_line
			(start 2.097532 3.949954)
			(end 2.097532 -3.949954)
			(stroke
				(width 0.1524)
				(type default)
			)
			(layer "F.SilkS")
		)
		(fp_poly
			(pts
				(xy -4.7498 -4.182872) (xy -4.7498 -3.166872) (xy -3.7338 -3.674872)
			)
			(stroke
				(width 0)
				(type default)
			)
			(fill yes)
			(layer "F.SilkS")
		)
		(fp_line
			(start -2.249932 -3.949954)
			(end -2.249932 3.949954)
			(stroke
				(width 0.1)
				(type default)
			)
			(layer "F.Fab")
		)
		(fp_line
			(start -2.249932 3.949954)
			(end 2.249932 3.949954)
			(stroke
				(width 0.1)
				(type default)
			)
			(layer "F.Fab")
		)
		(fp_line
			(start 2.249932 -3.949954)
			(end -2.249932 -3.949954)
			(stroke
				(width 0.1)
				(type default)
			)
			(layer "F.Fab")
		)
		(fp_line
			(start 2.249932 3.949954)
			(end 2.249932 -3.949954)
			(stroke
				(width 0.1)
				(type default)
			)
			(layer "F.Fab")
		)
		(fp_poly
			(pts
				(xy -4.7498 -4.182872) (xy -4.7498 -3.166872) (xy -3.7338 -3.674872)
			)
			(stroke
				(width 0)
				(type default)
			)
			(fill yes)
			(layer "F.Fab")
		)
		(pad "1" smd rect
			(at -2.925064 -3.674872 270)
			(size 0.6096 1.3716)
			(layers "F.Cu" "F.Mask" "F.Paste")
			(net "FM_SMB_CPU0_ALERT")
		)
		(pad "2" smd rect
			(at -2.925064 -2.925064 270)
			(size 0.4064 1.3716)
			(layers "F.Cu" "F.Mask" "F.Paste")
			(net "PD_SMB_OCP1_HP_ADD1")
		)
		(pad "3" smd rect
			(at -2.925064 -2.275078 270)
			(size 0.4064 1.3716)
			(layers "F.Cu" "F.Mask" "F.Paste")
			(net "PD_SMB_OCP1_HP_ADD2")
		)
		(pad "4" smd rect
			(at -2.925064 -1.625092 270)
			(size 0.4064 1.3716)
			(layers "F.Cu" "F.Mask" "F.Paste")
			(net "TP_PCA9555_0_P00")
		)
		(pad "5" smd rect
			(at -2.925064 -0.975106 270)
			(size 0.4064 1.3716)
			(layers "F.Cu" "F.Mask" "F.Paste")
			(net "TP_PCA9555_0_P01")
		)
		(pad "6" smd rect
			(at -2.925064 -0.32512 270)
			(size 0.4064 1.3716)
			(layers "F.Cu" "F.Mask" "F.Paste")
			(net "HP_OCP_V3_1_EN")
		)
		(pad "7" smd rect
			(at -2.925064 0.32512 270)
			(size 0.4064 1.3716)
			(layers "F.Cu" "F.Mask" "F.Paste")
			(net "HP_LVC3_OCP_V3_1_ATTN_OUT_SW_N")
		)
		(pad "8" smd rect
			(at -2.925064 0.975106 270)
			(size 0.4064 1.3716)
			(layers "F.Cu" "F.Mask" "F.Paste")
			(net "HP_LVC3_OCP_V3_1_PRSNT2_N")
		)
		(pad "9" smd rect
			(at -2.925064 1.625092 270)
			(size 0.4064 1.3716)
			(layers "F.Cu" "F.Mask" "F.Paste")
			(net "TP_PCA9555_0_P5")
		)
		(pad "10" smd rect
			(at -2.925064 2.275078 270)
			(size 0.4064 1.3716)
			(layers "F.Cu" "F.Mask" "F.Paste")
			(net "TP_PCA9555_0_P6")
		)
		(pad "11" smd rect
			(at -2.925064 2.925064 270)
			(size 0.4064 1.3716)
			(layers "F.Cu" "F.Mask" "F.Paste")
			(net "TP_PCA9555_0_P7")
		)
		(pad "12" smd rect
			(at -2.925064 3.674872 270)
			(size 0.6096 1.3716)
			(layers "F.Cu" "F.Mask" "F.Paste")
			(net "GND")
		)
		(pad "13" smd rect
			(at 2.925064 3.674872 270)
			(size 0.6096 1.3716)
			(layers "F.Cu" "F.Mask" "F.Paste")
			(net "TP_PCA9555_0_P10")
		)
		(pad "14" smd rect
			(at 2.925064 2.925064 270)
			(size 0.4064 1.3716)
			(layers "F.Cu" "F.Mask" "F.Paste")
			(net "TP_PCA9555_0_P11")
		)
		(pad "15" smd rect
			(at 2.925064 2.275078 270)
			(size 0.4064 1.3716)
			(layers "F.Cu" "F.Mask" "F.Paste")
			(net "TP_PCA9555_0_P12")
		)
		(pad "16" smd rect
			(at 2.925064 1.625092 270)
			(size 0.4064 1.3716)
			(layers "F.Cu" "F.Mask" "F.Paste")
			(net "TP_PCA9555_0_P13")
		)
		(pad "17" smd rect
			(at 2.925064 0.975106 270)
			(size 0.4064 1.3716)
			(layers "F.Cu" "F.Mask" "F.Paste")
			(net "TP_PCA9555_0_P14")
		)
		(pad "18" smd rect
			(at 2.925064 0.32512 270)
			(size 0.4064 1.3716)
			(layers "F.Cu" "F.Mask" "F.Paste")
			(net "TP_PCA9555_0_P15")
		)
		(pad "19" smd rect
			(at 2.925064 -0.32512 270)
			(size 0.4064 1.3716)
			(layers "F.Cu" "F.Mask" "F.Paste")
			(net "TP_PCA9555_0_P16")
		)
		(pad "20" smd rect
			(at 2.925064 -0.975106 270)
			(size 0.4064 1.3716)
			(layers "F.Cu" "F.Mask" "F.Paste")
			(net "TP_PCA9555_0_P17")
		)
		(pad "21" smd rect
			(at 2.925064 -1.625092 270)
			(size 0.4064 1.3716)
			(layers "F.Cu" "F.Mask" "F.Paste")
			(net "PD_SMB_OCP1_HP_ADD0")
		)
		(pad "22" smd rect
			(at 2.925064 -2.275078 270)
			(size 0.4064 1.3716)
			(layers "F.Cu" "F.Mask" "F.Paste")
			(net "SMB_PEHPCPU0_LVC3_R_SCL")
		)
		(pad "23" smd rect
			(at 2.925064 -2.925064 270)
			(size 0.4064 1.3716)
			(layers "F.Cu" "F.Mask" "F.Paste")
			(net "SMB_PEHPCPU0_LVC3_R_SDA")
		)
		(pad "24" smd rect
			(at 2.925064 -3.674872 270)
			(size 0.6096 1.3716)
			(layers "F.Cu" "F.Mask" "F.Paste")
			(net "P3V3_AUX")
		)
	)
)
